(kicad_pcb
	(version 20260206)
	(generator "pcbnew")
	(generator_version "10.0")
	(general
		(thickness 1.6)
		(legacy_teardrops no)
	)
	(paper "A4")
	(title_block
		(title "03242023_DA0F0TMBIJ0_F0T_Motherboard_J_brd_V01_OCP.brd")
		(comment 1 "Grand Teton / footprints 1204-1209 of 6105")
	)
	(layers
		(0 "F.Cu" signal "TOP")
		(4 "In1.Cu" signal "GND")
		(6 "In2.Cu" signal "IN1")
		(8 "In3.Cu" signal "GND1")
		(10 "In4.Cu" signal "IN2")
		(12 "In5.Cu" signal "GND2")
		(14 "In6.Cu" signal "IN3")
		(16 "In7.Cu" signal "GND3")
		(18 "In8.Cu" signal "VCC")
		(20 "In9.Cu" signal "VCC1")
		(22 "In10.Cu" signal "GND4")
		(24 "In11.Cu" signal "IN4")
		(26 "In12.Cu" signal "GND5")
		(28 "In13.Cu" signal "IN5")
		(30 "In14.Cu" signal "GND6")
		(32 "In15.Cu" signal "IN6")
		(34 "In16.Cu" signal "GND7")
		(2 "B.Cu" signal "BOTTOM")
		(9 "F.Adhes" user "F.Adhesive")
		(11 "B.Adhes" user "B.Adhesive")
		(13 "F.Paste" user "Package Geometry/Pastemask Top")
		(15 "B.Paste" user "Package Geometry/Pastemask Bottom")
		(5 "F.SilkS" user "Ref Des/Silkscreen Top")
		(7 "B.SilkS" user "Ref Des/Silkscreen Bottom")
		(1 "F.Mask" user "Board Geometry/Soldermask Top")
		(3 "B.Mask" user "Board Geometry/Soldermask Bottom")
		(17 "Dwgs.User" user "User.Drawings")
		(19 "Cmts.User" user "User.Comments")
		(21 "Eco1.User" user "User.Eco1")
		(23 "Eco2.User" user "User.Eco2")
		(25 "Edge.Cuts" user "Board Geometry/Outline")
		(27 "Margin" user)
		(31 "F.CrtYd" user "Package Geometry/Place Bound Top")
		(29 "B.CrtYd" user "Package Geometry/Place Bound Bottom")
		(35 "F.Fab" user "Ref Des/Assembly Top")
		(33 "B.Fab" user "Ref Des/Assembly Bottom")
	)
	(footprint ""
		(layer "F.Cu")
		(at 264.52449 -41.492678)
		(property "Reference" "JP4"
			(at -1.4097 -2.009648 0)
			(unlocked yes)
			(layer "F.SilkS")
			(effects
				(font
					(size 0.7874 0.5842)
					(thickness 0.1524)
				)
				(justify left)
			)
		)
		(property "Value" ""
			(at 0 0 0)
			(layer "F.Fab")
			(effects
				(font
					(size 1.27 1.27)
				)
			)
		)
		(duplicate_pad_numbers_are_jumpers no)
		(fp_line
			(start -1.249934 -1.320038)
			(end 1.249934 -1.320038)
			(stroke
				(width 0.1524)
				(type default)
			)
			(layer "F.SilkS")
		)
		(fp_line
			(start -1.249934 6.400038)
			(end -1.249934 -1.320038)
			(stroke
				(width 0.1524)
				(type default)
			)
			(layer "F.SilkS")
		)
		(fp_line
			(start 1.249934 -1.320038)
			(end 1.249934 6.400038)
			(stroke
				(width 0.1524)
				(type default)
			)
			(layer "F.SilkS")
		)
		(fp_line
			(start 1.249934 6.400038)
			(end -1.249934 6.400038)
			(stroke
				(width 0.1524)
				(type default)
			)
			(layer "F.SilkS")
		)
		(fp_poly
			(pts
				(xy -1.452372 0) (xy -2.5654 0.556514) (xy -2.5654 -0.556514)
			)
			(stroke
				(width 0)
				(type default)
			)
			(fill yes)
			(layer "F.SilkS")
		)
		(fp_line
			(start -1.249934 -1.320038)
			(end 1.249934 -1.320038)
			(stroke
				(width 0.1)
				(type default)
			)
			(layer "F.Fab")
		)
		(fp_line
			(start -1.249934 6.400038)
			(end -1.249934 -1.320038)
			(stroke
				(width 0.1)
				(type default)
			)
			(layer "F.Fab")
		)
		(fp_line
			(start 1.249934 -1.320038)
			(end 1.249934 6.400038)
			(stroke
				(width 0.1)
				(type default)
			)
			(layer "F.Fab")
		)
		(fp_line
			(start 1.249934 6.400038)
			(end -1.249934 6.400038)
			(stroke
				(width 0.1)
				(type default)
			)
			(layer "F.Fab")
		)
		(fp_poly
			(pts
				(xy -2.5654 -0.556514) (xy -1.452372 0) (xy -2.5654 0.556514)
			)
			(stroke
				(width 0)
				(type default)
			)
			(fill yes)
			(layer "F.Fab")
		)
		(fp_text user "3"
			(at -1.778 5.13207 0)
			(unlocked yes)
			(layer "F.SilkS")
			(effects
				(font
					(size 0.7874 0.5842)
					(thickness 0.1524)
				)
			)
		)
		(fp_text user "3"
			(at -1.1557 5.18287 0)
			(unlocked yes)
			(layer "B.SilkS")
			(effects
				(font
					(size 0.7874 0.5842)
					(thickness 0.1524)
				)
				(justify mirror)
			)
		)
		(fp_text user "1"
			(at -1.143 0.02667 0)
			(unlocked yes)
			(layer "B.SilkS")
			(effects
				(font
					(size 0.7874 0.5842)
					(thickness 0.1524)
				)
				(justify mirror)
			)
		)
		(fp_text user "3"
			(at -1.1557 5.18287 0)
			(unlocked yes)
			(layer "B.Fab")
			(effects
				(font
					(size 0.7874 0.5842)
					(thickness 0.1524)
				)
				(justify mirror)
			)
		)
		(fp_text user "1"
			(at -1.143 0.02667 0)
			(unlocked yes)
			(layer "B.Fab")
			(effects
				(font
					(size 0.7874 0.5842)
					(thickness 0.1524)
				)
				(justify mirror)
			)
		)
		(fp_text user "3"
			(at -1.778 5.13207 0)
			(unlocked yes)
			(layer "F.Fab")
			(effects
				(font
					(size 0.7874 0.5842)
					(thickness 0.1524)
				)
			)
		)
		(pad "1" thru_hole rect
			(at 0 0)
			(size 1.5494 1.5494)
			(drill 1.0414)
			(layers "*.Cu" "*.Mask")
			(remove_unused_layers no)
			(net "SMB_SML0_3V3AUX_PCH_SCL")
			(clearance 0)
			(padstack
				(mode front_inner_back)
				(layer "Inner"
					(shape circle)
					(size 1.5494 1.5494)
					(clearance 0)
				)
				(layer "B.Cu"
					(shape rect)
					(size 1.5494 1.5494)
					(clearance 0)
				)
			)
		)
		(pad "2" thru_hole circle
			(at 0 2.54)
			(size 1.5494 1.5494)
			(drill 1.0414)
			(layers "*.Cu" "*.Mask")
			(remove_unused_layers no)
			(net "GND")
			(clearance 0)
		)
		(pad "3" thru_hole circle
			(at 0 5.08)
			(size 1.5494 1.5494)
			(drill 1.0414)
			(layers "*.Cu" "*.Mask")
			(remove_unused_layers no)
			(net "SMB_SML0_3V3AUX_PCH_SDA")
			(clearance 0)
		)
	)
	(footprint ""
		(layer "F.Cu")
		(at 218.011502 -71.126858 180)
		(property "Reference" "PR3969"
			(at 0 0 180)
			(layer "F.SilkS")
			(hide yes)
			(effects
				(font
					(size 1.27 1.27)
				)
			)
		)
		(property "Value" ""
			(at 0 0 180)
			(layer "F.Fab")
			(effects
				(font
					(size 1.27 1.27)
				)
			)
		)
		(duplicate_pad_numbers_are_jumpers no)
		(fp_line
			(start 0.7874 0.4064)
			(end -0.7874 0.4064)
			(stroke
				(width 0.1524)
				(type default)
			)
			(layer "F.SilkS")
		)
		(fp_line
			(start 0.7874 -0.4064)
			(end 0.7874 0.4064)
			(stroke
				(width 0.1524)
				(type default)
			)
			(layer "F.SilkS")
		)
		(fp_line
			(start -0.7874 0.4064)
			(end -0.7874 -0.4064)
			(stroke
				(width 0.1524)
				(type default)
			)
			(layer "F.SilkS")
		)
		(fp_line
			(start -0.7874 -0.4064)
			(end 0.7874 -0.4064)
			(stroke
				(width 0.1524)
				(type default)
			)
			(layer "F.SilkS")
		)
		(fp_line
			(start 0.67945 0.3048)
			(end 0.120396 0.3048)
			(stroke
				(width 0.1)
				(type default)
			)
			(layer "F.Fab")
		)
		(fp_line
			(start 0.67945 -0.3048)
			(end 0.67945 0.3048)
			(stroke
				(width 0.1)
				(type default)
			)
			(layer "F.Fab")
		)
		(fp_line
			(start 0.12065 -0.2794)
			(end 0.12065 -0.3048)
			(stroke
				(width 0.1)
				(type default)
			)
			(layer "F.Fab")
		)
		(fp_line
			(start 0.12065 -0.3048)
			(end 0.67945 -0.3048)
			(stroke
				(width 0.1)
				(type default)
			)
			(layer "F.Fab")
		)
		(fp_line
			(start 0.120396 0.3048)
			(end 0.120396 0.2794)
			(stroke
				(width 0.1)
				(type default)
			)
			(layer "F.Fab")
		)
		(fp_line
			(start 0.120396 0.2794)
			(end -0.12065 0.2794)
			(stroke
				(width 0.1)
				(type default)
			)
			(layer "F.Fab")
		)
		(fp_line
			(start -0.12065 0.3048)
			(end -0.67945 0.3048)
			(stroke
				(width 0.1)
				(type default)
			)
			(layer "F.Fab")
		)
		(fp_line
			(start -0.12065 0.2794)
			(end -0.12065 0.3048)
			(stroke
				(width 0.1)
				(type default)
			)
			(layer "F.Fab")
		)
		(fp_line
			(start -0.12065 -0.2794)
			(end 0.12065 -0.2794)
			(stroke
				(width 0.1)
				(type default)
			)
			(layer "F.Fab")
		)
		(fp_line
			(start -0.12065 -0.305054)
			(end -0.12065 -0.2794)
			(stroke
				(width 0.1)
				(type default)
			)
			(layer "F.Fab")
		)
		(fp_line
			(start -0.67945 0.3048)
			(end -0.67945 -0.305054)
			(stroke
				(width 0.1)
				(type default)
			)
			(layer "F.Fab")
		)
		(fp_line
			(start -0.67945 -0.305054)
			(end -0.12065 -0.305054)
			(stroke
				(width 0.1)
				(type default)
			)
			(layer "F.Fab")
		)
		(pad "1" smd circle
			(at -0.40005 0 180)
			(size 0 0)
			(layers "F.Cu" "F.Mask" "F.Paste")
			(net "P3V3_E1S_CB_0")
		)
		(pad "2" smd circle
			(at 0.40005 0 180)
			(size 0 0)
			(layers "F.Cu" "F.Mask" "F.Paste")
			(net "GND")
		)
	)
	(footprint ""
		(layer "F.Cu")
		(at 174.635922 -25.846532 180)
		(property "Reference" "PC2239"
			(at 0 0 180)
			(layer "F.SilkS")
			(hide yes)
			(effects
				(font
					(size 1.27 1.27)
				)
			)
		)
		(property "Value" ""
			(at 0 0 180)
			(layer "F.Fab")
			(effects
				(font
					(size 1.27 1.27)
				)
			)
		)
		(duplicate_pad_numbers_are_jumpers no)
		(fp_line
			(start 1.2954 0.5842)
			(end -1.2954 0.5842)
			(stroke
				(width 0.1524)
				(type default)
			)
			(layer "F.SilkS")
		)
		(fp_line
			(start 1.2954 -0.5842)
			(end 1.2954 0.5842)
			(stroke
				(width 0.1524)
				(type default)
			)
			(layer "F.SilkS")
		)
		(fp_line
			(start 0 -0.5842)
			(end 0 0.5842)
			(stroke
				(width 0.1524)
				(type default)
			)
			(layer "F.SilkS")
		)
		(fp_line
			(start -1.2954 0.5842)
			(end -1.2954 -0.5842)
			(stroke
				(width 0.1524)
				(type default)
			)
			(layer "F.SilkS")
		)
		(fp_line
			(start -1.2954 -0.5842)
			(end 1.2954 -0.5842)
			(stroke
				(width 0.1524)
				(type default)
			)
			(layer "F.SilkS")
		)
		(fp_line
			(start 1.1938 0.4064)
			(end 0.8636 0.4064)
			(stroke
				(width 0.1)
				(type default)
			)
			(layer "F.Fab")
		)
		(fp_line
			(start 1.1938 -0.4064)
			(end 1.1938 0.4064)
			(stroke
				(width 0.1)
				(type default)
			)
			(layer "F.Fab")
		)
		(fp_line
			(start 0.8636 0.4572)
			(end -0.8636 0.4572)
			(stroke
				(width 0.1)
				(type default)
			)
			(layer "F.Fab")
		)
		(fp_line
			(start 0.8636 0.4064)
			(end 0.8636 0.4572)
			(stroke
				(width 0.1)
				(type default)
			)
			(layer "F.Fab")
		)
		(fp_line
			(start 0.8636 -0.4064)
			(end 1.1938 -0.4064)
			(stroke
				(width 0.1)
				(type default)
			)
			(layer "F.Fab")
		)
		(fp_line
			(start 0.8636 -0.4572)
			(end 0.8636 -0.4064)
			(stroke
				(width 0.1)
				(type default)
			)
			(layer "F.Fab")
		)
		(fp_line
			(start -0.8636 0.4572)
			(end -0.8636 0.4064)
			(stroke
				(width 0.1)
				(type default)
			)
			(layer "F.Fab")
		)
		(fp_line
			(start -0.8636 0.4064)
			(end -1.1938 0.4064)
			(stroke
				(width 0.1)
				(type default)
			)
			(layer "F.Fab")
		)
		(fp_line
			(start -0.8636 -0.4064)
			(end -0.8636 -0.4572)
			(stroke
				(width 0.1)
				(type default)
			)
			(layer "F.Fab")
		)
		(fp_line
			(start -0.8636 -0.4572)
			(end 0.8636 -0.4572)
			(stroke
				(width 0.1)
				(type default)
			)
			(layer "F.Fab")
		)
		(fp_line
			(start -1.1938 0.4064)
			(end -1.1938 -0.4064)
			(stroke
				(width 0.1)
				(type default)
			)
			(layer "F.Fab")
		)
		(fp_line
			(start -1.1938 -0.4064)
			(end -0.8636 -0.4064)
			(stroke
				(width 0.1)
				(type default)
			)
			(layer "F.Fab")
		)
		(pad "1" smd rect
			(at -0.7366 0 90)
			(size 0.7112 0.8128)
			(layers "F.Cu" "F.Mask" "F.Paste")
			(net "P12V_SCM_AVIN_PD")
		)
		(pad "2" smd rect
			(at 0.7366 0 90)
			(size 0.7112 0.8128)
			(layers "F.Cu" "F.Mask" "F.Paste")
			(net "GND")
		)
	)
	(footprint ""
		(layer "F.Cu")
		(at 241.28857 -111.212376 180)
		(property "Reference" "R1018"
			(at 0 0 180)
			(layer "F.SilkS")
			(hide yes)
			(effects
				(font
					(size 1.27 1.27)
				)
			)
		)
		(property "Value" ""
			(at 0 0 180)
			(layer "F.Fab")
			(effects
				(font
					(size 1.27 1.27)
				)
			)
		)
		(duplicate_pad_numbers_are_jumpers no)
		(fp_line
			(start 0.7874 0.4064)
			(end -0.7874 0.4064)
			(stroke
				(width 0.1524)
				(type default)
			)
			(layer "F.SilkS")
		)
		(fp_line
			(start 0.7874 -0.4064)
			(end 0.7874 0.4064)
			(stroke
				(width 0.1524)
				(type default)
			)
			(layer "F.SilkS")
		)
		(fp_line
			(start -0.7874 0.4064)
			(end -0.7874 -0.4064)
			(stroke
				(width 0.1524)
				(type default)
			)
			(layer "F.SilkS")
		)
		(fp_line
			(start -0.7874 -0.4064)
			(end 0.7874 -0.4064)
			(stroke
				(width 0.1524)
				(type default)
			)
			(layer "F.SilkS")
		)
		(fp_line
			(start 0.67945 0.3048)
			(end 0.120396 0.3048)
			(stroke
				(width 0.1)
				(type default)
			)
			(layer "F.Fab")
		)
		(fp_line
			(start 0.67945 -0.3048)
			(end 0.67945 0.3048)
			(stroke
				(width 0.1)
				(type default)
			)
			(layer "F.Fab")
		)
		(fp_line
			(start 0.12065 -0.2794)
			(end 0.12065 -0.3048)
			(stroke
				(width 0.1)
				(type default)
			)
			(layer "F.Fab")
		)
		(fp_line
			(start 0.12065 -0.3048)
			(end 0.67945 -0.3048)
			(stroke
				(width 0.1)
				(type default)
			)
			(layer "F.Fab")
		)
		(fp_line
			(start 0.120396 0.3048)
			(end 0.120396 0.2794)
			(stroke
				(width 0.1)
				(type default)
			)
			(layer "F.Fab")
		)
		(fp_line
			(start 0.120396 0.2794)
			(end -0.12065 0.2794)
			(stroke
				(width 0.1)
				(type default)
			)
			(layer "F.Fab")
		)
		(fp_line
			(start -0.12065 0.3048)
			(end -0.67945 0.3048)
			(stroke
				(width 0.1)
				(type default)
			)
			(layer "F.Fab")
		)
		(fp_line
			(start -0.12065 0.2794)
			(end -0.12065 0.3048)
			(stroke
				(width 0.1)
				(type default)
			)
			(layer "F.Fab")
		)
		(fp_line
			(start -0.12065 -0.2794)
			(end 0.12065 -0.2794)
			(stroke
				(width 0.1)
				(type default)
			)
			(layer "F.Fab")
		)
		(fp_line
			(start -0.12065 -0.305054)
			(end -0.12065 -0.2794)
			(stroke
				(width 0.1)
				(type default)
			)
			(layer "F.Fab")
		)
		(fp_line
			(start -0.67945 0.3048)
			(end -0.67945 -0.305054)
			(stroke
				(width 0.1)
				(type default)
			)
			(layer "F.Fab")
		)
		(fp_line
			(start -0.67945 -0.305054)
			(end -0.12065 -0.305054)
			(stroke
				(width 0.1)
				(type default)
			)
			(layer "F.Fab")
		)
		(pad "1" smd circle
			(at -0.40005 0 180)
			(size 0 0)
			(layers "F.Cu" "F.Mask" "F.Paste")
			(net "CLK_25M_CK440_CPU1_DN")
		)
		(pad "2" smd circle
			(at 0.40005 0 180)
			(size 0 0)
			(layers "F.Cu" "F.Mask" "F.Paste")
			(net "CLK_25M_CK440_CPU1_R_DN")
		)
	)
	(footprint ""
		(layer "F.Cu")
		(at 333.702152 -16.2052 90)
		(property "Reference" "R1749"
			(at 0 0 90)
			(layer "F.SilkS")
			(hide yes)
			(effects
				(font
					(size 1.27 1.27)
				)
			)
		)
		(property "Value" ""
			(at 0 0 90)
			(layer "F.Fab")
			(effects
				(font
					(size 1.27 1.27)
				)
			)
		)
		(duplicate_pad_numbers_are_jumpers no)
		(fp_line
			(start 0.7874 -0.4064)
			(end 0.7874 0.4064)
			(stroke
				(width 0.1524)
				(type default)
			)
			(layer "F.SilkS")
		)
		(fp_line
			(start -0.7874 -0.4064)
			(end 0.7874 -0.4064)
			(stroke
				(width 0.1524)
				(type default)
			)
			(layer "F.SilkS")
		)
		(fp_line
			(start 0.7874 0.4064)
			(end -0.7874 0.4064)
			(stroke
				(width 0.1524)
				(type default)
			)
			(layer "F.SilkS")
		)
		(fp_line
			(start -0.7874 0.4064)
			(end -0.7874 -0.4064)
			(stroke
				(width 0.1524)
				(type default)
			)
			(layer "F.SilkS")
		)
		(fp_line
			(start -0.12065 -0.305054)
			(end -0.12065 -0.2794)
			(stroke
				(width 0.1)
				(type default)
			)
			(layer "F.Fab")
		)
		(fp_line
			(start -0.67945 -0.305054)
			(end -0.12065 -0.305054)
			(stroke
				(width 0.1)
				(type default)
			)
			(layer "F.Fab")
		)
		(fp_line
			(start 0.67945 -0.3048)
			(end 0.67945 0.3048)
			(stroke
				(width 0.1)
				(type default)
			)
			(layer "F.Fab")
		)
		(fp_line
			(start 0.12065 -0.3048)
			(end 0.67945 -0.3048)
			(stroke
				(width 0.1)
				(type default)
			)
			(layer "F.Fab")
		)
		(fp_line
			(start 0.12065 -0.2794)
			(end 0.12065 -0.3048)
			(stroke
				(width 0.1)
				(type default)
			)
			(layer "F.Fab")
		)
		(fp_line
			(start -0.12065 -0.2794)
			(end 0.12065 -0.2794)
			(stroke
				(width 0.1)
				(type default)
			)
			(layer "F.Fab")
		)
		(fp_line
			(start 0.120396 0.2794)
			(end -0.12065 0.2794)
			(stroke
				(width 0.1)
				(type default)
			)
			(layer "F.Fab")
		)
		(fp_line
			(start -0.12065 0.2794)
			(end -0.12065 0.3048)
			(stroke
				(width 0.1)
				(type default)
			)
			(layer "F.Fab")
		)
		(fp_line
			(start 0.67945 0.3048)
			(end 0.120396 0.3048)
			(stroke
				(width 0.1)
				(type default)
			)
			(layer "F.Fab")
		)
		(fp_line
			(start 0.120396 0.3048)
			(end 0.120396 0.2794)
			(stroke
				(width 0.1)
				(type default)
			)
			(layer "F.Fab")
		)
		(fp_line
			(start -0.12065 0.3048)
			(end -0.67945 0.3048)
			(stroke
				(width 0.1)
				(type default)
			)
			(layer "F.Fab")
		)
		(fp_line
			(start -0.67945 0.3048)
			(end -0.67945 -0.305054)
			(stroke
				(width 0.1)
				(type default)
			)
			(layer "F.Fab")
		)
		(pad "1" smd circle
			(at -0.40005 0 90)
			(size 0 0)
			(layers "F.Cu" "F.Mask" "F.Paste")
			(net "FM_ESPI_PLD_R1_EN")
		)
		(pad "2" smd circle
			(at 0.40005 0 90)
			(size 0 0)
			(layers "F.Cu" "F.Mask" "F.Paste")
			(net "GND")
		)
	)
	(footprint ""
		(layer "F.Cu")
		(at 44.169584 -109.444282)
		(property "Reference" "R1791"
			(at 0 0 0)
			(layer "F.SilkS")
			(hide yes)
			(effects
				(font
					(size 1.27 1.27)
				)
			)
		)
		(property "Value" ""
			(at 0 0 0)
			(layer "F.Fab")
			(effects
				(font
					(size 1.27 1.27)
				)
			)
		)
		(duplicate_pad_numbers_are_jumpers no)
		(fp_line
			(start -0.7874 -0.4064)
			(end 0.7874 -0.4064)
			(stroke
				(width 0.1524)
				(type default)
			)
			(layer "F.SilkS")
		)
		(fp_line
			(start -0.7874 0.4064)
			(end -0.7874 -0.4064)
			(stroke
				(width 0.1524)
				(type default)
			)
			(layer "F.SilkS")
		)
		(fp_line
			(start 0.7874 -0.4064)
			(end 0.7874 0.4064)
			(stroke
				(width 0.1524)
				(type default)
			)
			(layer "F.SilkS")
		)
		(fp_line
			(start 0.7874 0.4064)
			(end -0.7874 0.4064)
			(stroke
				(width 0.1524)
				(type default)
			)
			(layer "F.SilkS")
		)
		(fp_line
			(start -0.67945 -0.305054)
			(end -0.12065 -0.305054)
			(stroke
				(width 0.1)
				(type default)
			)
			(layer "F.Fab")
		)
		(fp_line
			(start -0.67945 0.3048)
			(end -0.67945 -0.305054)
			(stroke
				(width 0.1)
				(type default)
			)
			(layer "F.Fab")
		)
		(fp_line
			(start -0.12065 -0.305054)
			(end -0.12065 -0.2794)
			(stroke
				(width 0.1)
				(type default)
			)
			(layer "F.Fab")
		)
		(fp_line
			(start -0.12065 -0.2794)
			(end 0.12065 -0.2794)
			(stroke
				(width 0.1)
				(type default)
			)
			(layer "F.Fab")
		)
		(fp_line
			(start -0.12065 0.2794)
			(end -0.12065 0.3048)
			(stroke
				(width 0.1)
				(type default)
			)
			(layer "F.Fab")
		)
		(fp_line
			(start -0.12065 0.3048)
			(end -0.67945 0.3048)
			(stroke
				(width 0.1)
				(type default)
			)
			(layer "F.Fab")
		)
		(fp_line
			(start 0.120396 0.2794)
			(end -0.12065 0.2794)
			(stroke
				(width 0.1)
				(type default)
			)
			(layer "F.Fab")
		)
		(fp_line
			(start 0.120396 0.3048)
			(end 0.120396 0.2794)
			(stroke
				(width 0.1)
				(type default)
			)
			(layer "F.Fab")
		)
		(fp_line
			(start 0.12065 -0.3048)
			(end 0.67945 -0.3048)
			(stroke
				(width 0.1)
				(type default)
			)
			(layer "F.Fab")
		)
		(fp_line
			(start 0.12065 -0.2794)
			(end 0.12065 -0.3048)
			(stroke
				(width 0.1)
				(type default)
			)
			(layer "F.Fab")
		)
		(fp_line
			(start 0.67945 -0.3048)
			(end 0.67945 0.3048)
			(stroke
				(width 0.1)
				(type default)
			)
			(layer "F.Fab")
		)
		(fp_line
			(start 0.67945 0.3048)
			(end 0.120396 0.3048)
			(stroke
				(width 0.1)
				(type default)
			)
			(layer "F.Fab")
		)
		(pad "1" smd circle
			(at -0.40005 0)
			(size 0 0)
			(layers "F.Cu" "F.Mask" "F.Paste")
			(net "P5V_ADC")
		)
		(pad "2" smd circle
			(at 0.40005 0)
			(size 0 0)
			(layers "F.Cu" "F.Mask" "F.Paste")
			(net "GND")
		)
	)
)
